(kicad_pcb
	(version 20260206)
	(generator "pcbnew")
	(generator_version "10.0")
	(general
		(thickness 1.6)
		(legacy_teardrops no)
	)
	(paper "A4")
	(title_block
		(title "baseboard — 13948-1b.1110WZS1818.brd")
		(comment 1 "Honey Badger (Wiwynn) / footprints 1016-1018 of 2523")
	)
	(layers
		(0 "F.Cu" signal "TOP")
		(4 "In1.Cu" signal "L2GND")
		(6 "In2.Cu" signal "L3")
		(8 "In3.Cu" signal "L4VCC")
		(10 "In4.Cu" signal "L5VCC")
		(12 "In5.Cu" signal "L6")
		(14 "In6.Cu" signal "L7GND")
		(2 "B.Cu" signal "BOTTOM")
		(9 "F.Adhes" user "F.Adhesive")
		(11 "B.Adhes" user "B.Adhesive")
		(13 "F.Paste" user "Package Geometry/Pastemask Top")
		(15 "B.Paste" user "Package Geometry/Pastemask Bottom")
		(5 "F.SilkS" user "Ref Des/Silkscreen Top")
		(7 "B.SilkS" user "Ref Des/Silkscreen Bottom")
		(1 "F.Mask" user "Board Geometry/Soldermask Top")
		(3 "B.Mask" user "Board Geometry/Soldermask Bottom")
		(17 "Dwgs.User" user "User.Drawings")
		(19 "Cmts.User" user "User.Comments")
		(21 "Eco1.User" user "User.Eco1")
		(23 "Eco2.User" user "User.Eco2")
		(25 "Edge.Cuts" user "Board Geometry/Outline")
		(27 "Margin" user)
		(31 "F.CrtYd" user "Package Geometry/Place Bound Top")
		(29 "B.CrtYd" user "Package Geometry/Place Bound Bottom")
		(35 "F.Fab" user "Ref Des/Assembly Top")
		(33 "B.Fab" user "Ref Des/Assembly Bottom")
	)
	(footprint ""
		(layer "F.Cu")
		(at 345.985084 -6.500114 180)
		(property "Reference" "CN3"
			(at 0 0 180)
			(layer "F.SilkS")
			(hide yes)
			(effects
				(font
					(size 1.27 1.27)
				)
			)
		)
		(property "Value" "JWT-CONN14A-1-GP"
			(at -9.8298 -4.064 180)
			(unlocked yes)
			(layer "F.Fab")
			(hide yes)
			(effects
				(font
					(size 1.016 1.016)
					(thickness 0.1524)
				)
			)
		)
		(property "Device Type" "A2005WR0-2CX7P-6T"
			(at -9.8298 -5.588 180)
			(unlocked yes)
			(layer "F.Fab")
			(hide yes)
			(effects
				(font
					(size 1.016 1.016)
					(thickness 0.1524)
				)
			)
		)
		(duplicate_pad_numbers_are_jumpers no)
		(fp_line
			(start 8.5852 -0.7366)
			(end 6.8834 -0.7366)
			(stroke
				(width 0.1524)
				(type default)
			)
			(layer "F.SilkS")
		)
		(fp_line
			(start 8.5852 -7.6454)
			(end 8.5852 -0.7366)
			(stroke
				(width 0.1524)
				(type default)
			)
			(layer "F.SilkS")
		)
		(fp_line
			(start 6.8834 1.8796)
			(end -6.8834 1.8796)
			(stroke
				(width 0.1524)
				(type default)
			)
			(layer "F.SilkS")
		)
		(fp_line
			(start 6.8834 -0.7366)
			(end 6.8834 1.8796)
			(stroke
				(width 0.1524)
				(type default)
			)
			(layer "F.SilkS")
		)
		(fp_line
			(start 1.1938 -7.6454)
			(end 1.1938 -7.1374)
			(stroke
				(width 0.1524)
				(type default)
			)
			(layer "F.SilkS")
		)
		(fp_line
			(start -1.1938 -7.1374)
			(end 1.1938 -7.1374)
			(stroke
				(width 0.1524)
				(type default)
			)
			(layer "F.SilkS")
		)
		(fp_line
			(start -1.1938 -7.6454)
			(end -1.1938 -7.1374)
			(stroke
				(width 0.1524)
				(type default)
			)
			(layer "F.SilkS")
		)
		(fp_line
			(start -5.1689 2.0574)
			(end -7.0739 2.0574)
			(stroke
				(width 0.508)
				(type default)
			)
			(layer "F.SilkS")
		)
		(fp_line
			(start -6.8834 1.8796)
			(end -6.8834 -0.7366)
			(stroke
				(width 0.1524)
				(type default)
			)
			(layer "F.SilkS")
		)
		(fp_line
			(start -6.8834 -0.7366)
			(end -8.5852 -0.7366)
			(stroke
				(width 0.1524)
				(type default)
			)
			(layer "F.SilkS")
		)
		(fp_line
			(start -7.0739 2.0574)
			(end -7.0739 0.1524)
			(stroke
				(width 0.508)
				(type default)
			)
			(layer "F.SilkS")
		)
		(fp_line
			(start -8.5852 -0.7366)
			(end -8.5852 -7.6454)
			(stroke
				(width 0.1524)
				(type default)
			)
			(layer "F.SilkS")
		)
		(fp_line
			(start -8.5852 -7.6454)
			(end 8.5852 -7.6454)
			(stroke
				(width 0.1524)
				(type default)
			)
			(layer "F.SilkS")
		)
		(fp_circle
			(center 5.99948 0.99949)
			(end 5.00888 0.99949)
			(stroke
				(width 0.3048)
				(type default)
			)
			(fill no)
			(layer "F.SilkS")
		)
		(fp_circle
			(center 5.99948 -0.99949)
			(end 5.00888 -0.99949)
			(stroke
				(width 0.3048)
				(type default)
			)
			(fill no)
			(layer "F.SilkS")
		)
		(fp_circle
			(center 4.0005 0.99949)
			(end 3.0099 0.99949)
			(stroke
				(width 0.3048)
				(type default)
			)
			(fill no)
			(layer "F.SilkS")
		)
		(fp_circle
			(center 4.0005 -0.99949)
			(end 3.0099 -0.99949)
			(stroke
				(width 0.3048)
				(type default)
			)
			(fill no)
			(layer "F.SilkS")
		)
		(fp_circle
			(center 2.00025 0.99949)
			(end 1.00965 0.99949)
			(stroke
				(width 0.3048)
				(type default)
			)
			(fill no)
			(layer "F.SilkS")
		)
		(fp_circle
			(center 2.00025 -0.99949)
			(end 1.00965 -0.99949)
			(stroke
				(width 0.3048)
				(type default)
			)
			(fill no)
			(layer "F.SilkS")
		)
		(fp_circle
			(center 0 0.99949)
			(end -0.9906 0.99949)
			(stroke
				(width 0.3048)
				(type default)
			)
			(fill no)
			(layer "F.SilkS")
		)
		(fp_circle
			(center 0 -0.99949)
			(end -0.9906 -0.99949)
			(stroke
				(width 0.3048)
				(type default)
			)
			(fill no)
			(layer "F.SilkS")
		)
		(fp_circle
			(center -2.00025 0.99949)
			(end -2.99085 0.99949)
			(stroke
				(width 0.3048)
				(type default)
			)
			(fill no)
			(layer "F.SilkS")
		)
		(fp_circle
			(center -2.00025 -0.99949)
			(end -2.99085 -0.99949)
			(stroke
				(width 0.3048)
				(type default)
			)
			(fill no)
			(layer "F.SilkS")
		)
		(fp_circle
			(center -4.0005 0.99949)
			(end -4.9911 0.99949)
			(stroke
				(width 0.3048)
				(type default)
			)
			(fill no)
			(layer "F.SilkS")
		)
		(fp_circle
			(center -4.0005 -0.99949)
			(end -4.9911 -0.99949)
			(stroke
				(width 0.3048)
				(type default)
			)
			(fill no)
			(layer "F.SilkS")
		)
		(fp_circle
			(center -5.99948 0.99949)
			(end -6.99008 0.99949)
			(stroke
				(width 0.3048)
				(type default)
			)
			(fill no)
			(layer "F.SilkS")
		)
		(fp_circle
			(center -5.99948 -0.99949)
			(end -6.99008 -0.99949)
			(stroke
				(width 0.3048)
				(type default)
			)
			(fill no)
			(layer "F.SilkS")
		)
		(fp_poly
			(pts
				(xy -6.2484 1.2446) (xy 6.2484 1.2446) (xy 6.2484 -0.9906) (xy 8.3312 -0.9906) (xy 8.3312 -7.3914)
				(xy -8.3312 -7.3914) (xy -8.3312 -0.9906) (xy -6.2484 -0.9906)
			)
			(stroke
				(width 0)
				(type default)
			)
			(fill no)
			(layer "F.CrtYd")
		)
		(fp_poly
			(pts
				(xy -7.1374 2.1336) (xy -7.1374 -0.4826) (xy -8.8392 -0.4826) (xy -8.8392 -7.8994) (xy 8.8392 -7.8994)
				(xy 8.8392 -0.4826) (xy 7.1374 -0.4826) (xy 7.1374 -0.00635) (xy 6.2484 -0.00635) (xy 6.2484 -0.9906)
				(xy 8.3312 -0.9906) (xy 8.3312 -7.3914) (xy -8.3312 -7.3914) (xy -8.3312 -0.9906) (xy -6.2484 -0.9906)
				(xy -6.2484 1.2446) (xy 6.2484 1.2446) (xy 6.2484 0.00635) (xy 7.1374 0.00635) (xy 7.1374 2.1336)
			)
			(stroke
				(width 0)
				(type default)
			)
			(fill no)
			(layer "F.CrtYd")
		)
		(fp_poly
			(pts
				(xy -7.1374 2.1336) (xy -7.1374 -0.4826) (xy -8.8392 -0.4826) (xy -8.8392 -7.8994) (xy 8.8392 -7.8994)
				(xy 8.8392 -0.4826) (xy 7.1374 -0.4826) (xy 7.1374 2.1336)
			)
			(stroke
				(width 0)
				(type default)
			)
			(fill no)
			(layer "F.Fab")
		)
		(pad "1" thru_hole circle
			(at -5.99948 0.99949 180)
			(size 1.27 1.27)
			(drill 0.889)
			(layers "*.Cu" "*.Mask")
			(remove_unused_layers no)
			(net "LOW_HEX_0")
			(clearance 0.1651)
			(thermal_gap 0.1651)
		)
		(pad "2" thru_hole circle
			(at -5.99948 -0.99949 180)
			(size 1.27 1.27)
			(drill 0.889)
			(layers "*.Cu" "*.Mask")
			(remove_unused_layers no)
			(net "LOW_HEX_1")
			(clearance 0.1651)
			(thermal_gap 0.1651)
		)
		(pad "3" thru_hole circle
			(at -4.0005 0.99949 180)
			(size 1.27 1.27)
			(drill 0.889)
			(layers "*.Cu" "*.Mask")
			(remove_unused_layers no)
			(net "LOW_HEX_2")
			(clearance 0.1651)
			(thermal_gap 0.1651)
		)
		(pad "4" thru_hole circle
			(at -4.0005 -0.99949 180)
			(size 1.27 1.27)
			(drill 0.889)
			(layers "*.Cu" "*.Mask")
			(remove_unused_layers no)
			(net "LOW_HEX_3")
			(clearance 0.1651)
			(thermal_gap 0.1651)
		)
		(pad "5" thru_hole circle
			(at -2.00025 0.99949 180)
			(size 1.27 1.27)
			(drill 0.889)
			(layers "*.Cu" "*.Mask")
			(remove_unused_layers no)
			(net "HIGH_HEX_0")
			(clearance 0.1651)
			(thermal_gap 0.1651)
		)
		(pad "6" thru_hole circle
			(at -2.00025 -0.99949 180)
			(size 1.27 1.27)
			(drill 0.889)
			(layers "*.Cu" "*.Mask")
			(remove_unused_layers no)
			(net "HIGH_HEX_1")
			(clearance 0.1651)
			(thermal_gap 0.1651)
		)
		(pad "7" thru_hole circle
			(at 0 0.99949 180)
			(size 1.27 1.27)
			(drill 0.889)
			(layers "*.Cu" "*.Mask")
			(remove_unused_layers no)
			(net "HIGH_HEX_2")
			(clearance 0.1651)
			(thermal_gap 0.1651)
		)
		(pad "8" thru_hole circle
			(at 0 -0.99949 180)
			(size 1.27 1.27)
			(drill 0.889)
			(layers "*.Cu" "*.Mask")
			(remove_unused_layers no)
			(net "HIGH_HEX_3")
			(clearance 0.1651)
			(thermal_gap 0.1651)
		)
		(pad "9" thru_hole circle
			(at 2.00025 0.99949 180)
			(size 1.27 1.27)
			(drill 0.889)
			(layers "*.Cu" "*.Mask")
			(remove_unused_layers no)
			(net "DEBUG_CARD_TX")
			(clearance 0.1651)
			(thermal_gap 0.1651)
		)
		(pad "10" thru_hole circle
			(at 2.00025 -0.99949 180)
			(size 1.27 1.27)
			(drill 0.889)
			(layers "*.Cu" "*.Mask")
			(remove_unused_layers no)
			(net "DEBUG_CARD_RX")
			(clearance 0.1651)
			(thermal_gap 0.1651)
		)
		(pad "11" thru_hole circle
			(at 4.0005 0.99949 180)
			(size 1.27 1.27)
			(drill 0.889)
			(layers "*.Cu" "*.Mask")
			(remove_unused_layers no)
			(net "DP_RST_N")
			(clearance 0.1651)
			(thermal_gap 0.1651)
		)
		(pad "12" thru_hole circle
			(at 4.0005 -0.99949 180)
			(size 1.27 1.27)
			(drill 0.889)
			(layers "*.Cu" "*.Mask")
			(remove_unused_layers no)
			(net "UART COUNT")
			(clearance 0.1651)
			(thermal_gap 0.1651)
		)
		(pad "13" thru_hole circle
			(at 5.99948 0.99949 180)
			(size 1.27 1.27)
			(drill 0.889)
			(layers "*.Cu" "*.Mask")
			(remove_unused_layers no)
			(net "GND")
			(clearance 0.1651)
			(thermal_gap 0.1651)
		)
		(pad "14" thru_hole circle
			(at 5.99948 -0.99949 180)
			(size 1.27 1.27)
			(drill 0.889)
			(layers "*.Cu" "*.Mask")
			(remove_unused_layers no)
			(net "P5V_STBY")
			(clearance 0.1651)
			(thermal_gap 0.1651)
		)
	)
	(footprint ""
		(layer "F.Cu")
		(at 346.858336 -76.538328)
		(property "Reference" "SKT3"
			(at 0 0 0)
			(layer "F.SilkS")
			(hide yes)
			(effects
				(font
					(size 1.27 1.27)
				)
			)
		)
		(property "Value" "SKT-SPI16P-GP-U"
			(at -8.9916 4.641596 0)
			(unlocked yes)
			(layer "F.Fab")
			(hide yes)
			(effects
				(font
					(size 1.016 1.016)
					(thickness 0.1524)
				)
			)
		)
		(property "Device Type" "SKT-SOIC16-153139H258"
			(at -8.9916 3.117596 0)
			(unlocked yes)
			(layer "F.Fab")
			(hide yes)
			(effects
				(font
					(size 1.016 1.016)
					(thickness 0.1524)
				)
			)
		)
		(duplicate_pad_numbers_are_jumpers no)
		(fp_line
			(start -7.8994 -6.4008)
			(end -7.8994 6.4008)
			(stroke
				(width 0.1524)
				(type default)
			)
			(layer "F.SilkS")
		)
		(fp_line
			(start -7.8994 6.4008)
			(end 7.8994 6.4008)
			(stroke
				(width 0.1524)
				(type default)
			)
			(layer "F.SilkS")
		)
		(fp_line
			(start 6.7183 0.0762)
			(end 7.8994 1.2573)
			(stroke
				(width 0.1524)
				(type default)
			)
			(layer "F.SilkS")
		)
		(fp_line
			(start 7.7216 -6.223)
			(end 7.7216 -3.6576)
			(stroke
				(width 0.508)
				(type default)
			)
			(layer "F.SilkS")
		)
		(fp_line
			(start 7.8867 -1.0922)
			(end 6.7183 0.0762)
			(stroke
				(width 0.1524)
				(type default)
			)
			(layer "F.SilkS")
		)
		(fp_line
			(start 7.8994 -6.4008)
			(end -7.8994 -6.4008)
			(stroke
				(width 0.1524)
				(type default)
			)
			(layer "F.SilkS")
		)
		(fp_line
			(start 7.8994 6.4008)
			(end 7.8994 -6.4008)
			(stroke
				(width 0.1524)
				(type default)
			)
			(layer "F.SilkS")
		)
		(fp_poly
			(pts
				(xy -4.699 -3.855466) (xy -4.699 3.855466) (xy 4.699 3.855466) (xy 4.699 -3.855466)
			)
			(stroke
				(width 0)
				(type default)
			)
			(fill yes)
			(layer "F.SilkS")
		)
		(fp_rect
			(start -8.1534 -6.4008)
			(end 8.1534 -12.5222)
			(stroke
				(width 0)
				(type default)
			)
			(fill no)
			(layer "F.CrtYd")
		)
		(fp_rect
			(start -8.1534 11.6078)
			(end 8.1534 6.4008)
			(stroke
				(width 0)
				(type default)
			)
			(fill no)
			(layer "F.CrtYd")
		)
		(fp_poly
			(pts
				(xy -8.1534 6.4008) (xy -8.1534 -6.4008) (xy -6.2484 -6.4008) (xy -6.2484 -2.6416) (xy -7.6454 -2.6416)
				(xy -7.6454 2.6416) (xy -6.2484 2.6416) (xy -6.2484 6.4008)
			)
			(stroke
				(width 0)
				(type default)
			)
			(fill no)
			(layer "F.CrtYd")
		)
		(fp_poly
			(pts
				(xy 6.2484 -6.4008) (xy 8.1534 -6.4008) (xy 8.1534 6.4008) (xy 6.2484 6.4008) (xy 6.2484 2.6416)
				(xy 7.6454 2.6416) (xy 7.6454 -2.6416) (xy 6.2484 -2.6416)
			)
			(stroke
				(width 0)
				(type default)
			)
			(fill no)
			(layer "F.CrtYd")
		)
		(fp_poly
			(pts
				(xy 6.2484 -6.4008) (xy -6.2484 -6.4008) (xy -6.2484 -2.6416) (xy -7.6454 -2.6416) (xy -7.6454 2.6416)
				(xy -6.2484 2.6416) (xy -6.2484 6.4008) (xy 6.2484 6.4008) (xy 6.2484 2.6416) (xy 7.6454 2.6416)
				(xy 7.6454 -2.6416) (xy 6.2484 -2.6416)
			)
			(stroke
				(width 0)
				(type default)
			)
			(fill no)
			(layer "F.CrtYd")
		)
		(fp_rect
			(start -8.1534 11.6078)
			(end 8.1534 -12.5222)
			(stroke
				(width 0)
				(type default)
			)
			(fill no)
			(layer "F.Fab")
		)
		(pad "1" smd rect
			(at 4.445 -4.896866)
			(size 0.508 1.6764)
			(layers "F.Cu" "F.Mask" "F.Paste")
			(net "PU_IBMC_BT_HOLD_N")
		)
		(pad "2" smd rect
			(at 3.175 -4.896866)
			(size 0.508 1.6764)
			(layers "F.Cu" "F.Mask" "F.Paste")
			(net "P3V3_STBY")
		)
		(pad "3" smd rect
			(at 1.905 -4.896866)
			(size 0.508 1.6764)
			(layers "F.Cu" "F.Mask" "F.Paste")
			(net "Net_2087")
		)
		(pad "4" smd rect
			(at 0.635 -4.896866)
			(size 0.508 1.6764)
			(layers "F.Cu" "F.Mask" "F.Paste")
			(net "Net_2086")
		)
		(pad "5" smd rect
			(at -0.635 -4.896866)
			(size 0.508 1.6764)
			(layers "F.Cu" "F.Mask" "F.Paste")
			(net "Net_2085")
		)
		(pad "6" smd rect
			(at -1.905 -4.896866)
			(size 0.508 1.6764)
			(layers "F.Cu" "F.Mask" "F.Paste")
			(net "Net_2084")
		)
		(pad "7" smd rect
			(at -3.175 -4.896866)
			(size 0.508 1.6764)
			(layers "F.Cu" "F.Mask" "F.Paste")
			(net "FLA_CS_R")
		)
		(pad "8" smd rect
			(at -4.445 -4.896866)
			(size 0.508 1.6764)
			(layers "F.Cu" "F.Mask" "F.Paste")
			(net "ROMD2_R")
		)
		(pad "9" smd rect
			(at -4.445 4.896866)
			(size 0.508 1.6764)
			(layers "F.Cu" "F.Mask" "F.Paste")
			(net "FLA_WPN")
		)
		(pad "10" smd rect
			(at -3.175 4.896866)
			(size 0.508 1.6764)
			(layers "F.Cu" "F.Mask" "F.Paste")
			(net "GND")
		)
		(pad "11" smd rect
			(at -1.905 4.896866)
			(size 0.508 1.6764)
			(layers "F.Cu" "F.Mask" "F.Paste")
			(net "Net_2091")
		)
		(pad "12" smd rect
			(at -0.635 4.896866)
			(size 0.508 1.6764)
			(layers "F.Cu" "F.Mask" "F.Paste")
			(net "Net_2090")
		)
		(pad "13" smd rect
			(at 0.635 4.896866)
			(size 0.508 1.6764)
			(layers "F.Cu" "F.Mask" "F.Paste")
			(net "Net_2089")
		)
		(pad "14" smd rect
			(at 1.905 4.896866)
			(size 0.508 1.6764)
			(layers "F.Cu" "F.Mask" "F.Paste")
			(net "Net_2088")
		)
		(pad "15" smd rect
			(at 3.175 4.896866)
			(size 0.508 1.6764)
			(layers "F.Cu" "F.Mask" "F.Paste")
			(net "ROMD1_R")
		)
		(pad "16" smd rect
			(at 4.445 4.896866)
			(size 0.508 1.6764)
			(layers "F.Cu" "F.Mask" "F.Paste")
			(net "ROMD0_R")
		)
	)
	(footprint ""
		(layer "F.Cu")
		(at 199.263 -138.811 90)
		(property "Reference" "SR765"
			(at 0 0 90)
			(layer "F.SilkS")
			(hide yes)
			(effects
				(font
					(size 1.27 1.27)
				)
			)
		)
		(property "Value" "4K7R2F-GP"
			(at 0.064008 -3.993896 90)
			(unlocked yes)
			(layer "F.Fab")
			(hide yes)
			(effects
				(font
					(size 1.016 1.016)
					(thickness 0.1524)
				)
			)
		)
		(property "Device Type" "R402H16"
			(at 0.064008 -5.517896 90)
			(unlocked yes)
			(layer "F.Fab")
			(hide yes)
			(effects
				(font
					(size 1.016 1.016)
					(thickness 0.1524)
				)
			)
		)
		(duplicate_pad_numbers_are_jumpers no)
		(fp_line
			(start 0.508 -0.9398)
			(end -0.508 -0.9398)
			(stroke
				(width 0.1524)
				(type default)
			)
			(layer "F.SilkS")
		)
		(fp_line
			(start -0.508 -0.9398)
			(end -0.508 0.9398)
			(stroke
				(width 0.1524)
				(type default)
			)
			(layer "F.SilkS")
		)
		(fp_rect
			(start -0.508 0.9398)
			(end 0.508 -0.9398)
			(stroke
				(width 0)
				(type default)
			)
			(fill no)
			(layer "F.CrtYd")
		)
		(fp_rect
			(start -0.508 0.9398)
			(end 0.508 -0.9398)
			(stroke
				(width 0)
				(type default)
			)
			(fill no)
			(layer "F.Fab")
		)
		(pad "1" smd custom
			(at 0 -0.4445 90)
			(size 0.1397 0.1397)
			(layers "F.Cu" "F.Mask" "F.Paste")
			(net "EXP_EEPROM_A0")
			(options
				(clearance outline)
				(anchor circle)
			)
			(primitives
				(gr_poly
					(pts
						(arc
							(start -0.1778 -0.2794)
							(mid -0.249642 -0.249642)
							(end -0.2794 -0.1778)
						)
						(arc
							(start -0.2794 0.1778)
							(mid -0.249642 0.249642)
							(end -0.1778 0.2794)
						)
						(arc
							(start 0.1778 0.2794)
							(mid 0.249642 0.249642)
							(end 0.2794 0.1778)
						)
						(arc
							(start 0.2794 -0.1778)
							(mid 0.249642 -0.249642)
							(end 0.1778 -0.2794)
						)
					)
					(width 0)
					(fill yes)
				)
			)
		)
		(pad "2" smd custom
			(at 0 0.4445 90)
			(size 0.1397 0.1397)
			(layers "F.Cu" "F.Mask" "F.Paste")
			(net "GND")
			(options
				(clearance outline)
				(anchor circle)
			)
			(primitives
				(gr_poly
					(pts
						(arc
							(start -0.1778 -0.2794)
							(mid -0.249642 -0.249642)
							(end -0.2794 -0.1778)
						)
						(arc
							(start -0.2794 0.1778)
							(mid -0.249642 0.249642)
							(end -0.1778 0.2794)
						)
						(arc
							(start 0.1778 0.2794)
							(mid 0.249642 0.249642)
							(end 0.2794 0.1778)
						)
						(arc
							(start 0.2794 -0.1778)
							(mid 0.249642 -0.249642)
							(end 0.1778 -0.2794)
						)
					)
					(width 0)
					(fill yes)
				)
			)
		)
	)
)
